# BASEBOARD_FAB2 (Tioga Pass) — schematic netlist excerpt (pin names and nets, part order shuffled) for the footprints in the layout excerpt that follows; sources: Cadence DE-HDL packaged netlist, KiCad conversion of Wiwynn_Tioga_Pass_MB.brd

C5G54  CAP_A  22.0UF 4V 20% X6S  pkg 0603V  page 242 : A = PVDDQ_ABC ; B = GND
R8D42  RES  100.0 1% CHIP  pkg 0402  page 196 : A = PWRGD_P12V_MAIN_R ; B = PWRGD_P12V_MAIN
R2N19  RES  49.9 1% CHIP  pkg 0402  page 178 : A = SGPIO_PCH_SSATA_LOAD ; B = SGPIO_PCH_SSATA_LOAD_R

(kicad_pcb
	(version 20260206)
	(generator "pcbnew")
	(generator_version "10.0")
	(general
		(thickness 1.6)
		(legacy_teardrops no)
	)
	(paper "A4")
	(title_block
		(title "Wiwynn_Tioga_Pass_MB.brd")
		(comment 1 "Tioga Pass / footprints 2364-2366 of 4770")
	)
	(layers
		(0 "F.Cu" signal "TOP")
		(4 "In1.Cu" signal "L2GND")
		(6 "In2.Cu" signal "L3")
		(8 "In3.Cu" signal "L4GND")
		(10 "In4.Cu" signal "L5")
		(12 "In5.Cu" signal "L6GND")
		(14 "In6.Cu" signal "L7VCC")
		(16 "In7.Cu" signal "L8VCC")
		(18 "In8.Cu" signal "L9GND")
		(20 "In9.Cu" signal "L10")
		(22 "In10.Cu" signal "L11GND")
		(24 "In11.Cu" signal "L12")
		(26 "In12.Cu" signal "L13GND")
		(2 "B.Cu" signal "BOTTOM")
		(9 "F.Adhes" user "F.Adhesive")
		(11 "B.Adhes" user "B.Adhesive")
		(13 "F.Paste" user "Package Geometry/Pastemask Top")
		(15 "B.Paste" user "Package Geometry/Pastemask Bottom")
		(5 "F.SilkS" user "Ref Des/Silkscreen Top")
		(7 "B.SilkS" user "Ref Des/Silkscreen Bottom")
		(1 "F.Mask" user "Board Geometry/Soldermask Top")
		(3 "B.Mask" user "Board Geometry/Soldermask Bottom")
		(17 "Dwgs.User" user "User.Drawings")
		(19 "Cmts.User" user "User.Comments")
		(21 "Eco1.User" user "User.Eco1")
		(23 "Eco2.User" user "User.Eco2")
		(25 "Edge.Cuts" user "Board Geometry/Outline")
		(27 "Margin" user)
		(31 "F.CrtYd" user "Package Geometry/Place Bound Top")
		(29 "B.CrtYd" user "Package Geometry/Place Bound Bottom")
		(35 "F.Fab" user "Ref Des/Assembly Top")
		(33 "B.Fab" user "Ref Des/Assembly Bottom")
	)
	(footprint ""
		(layer "B.Cu")
		(at 390.906 -87.4395)
		(property "Reference" "R2N19"
			(at 0.8382 -0.67818 0)
			(unlocked yes)
			(layer "B.SilkS")
			(effects
				(font
					(size 0.4064 0.254)
					(thickness 0.1524)
				)
				(justify left mirror)
			)
		)
		(property "Value" ""
			(at 0 0 0)
			(layer "B.Fab")
			(effects
				(font
					(size 1.27 1.27)
				)
				(justify mirror)
			)
		)
		(duplicate_pad_numbers_are_jumpers no)
		(fp_poly
			(pts
				(xy 0.2794 -0.1016) (xy -0.2794 -0.1016) (xy -0.2794 0.9906) (xy 0.2794 0.9906)
			)
			(stroke
				(width 0)
				(type default)
			)
			(fill no)
			(layer "B.CrtYd")
		)
		(fp_line
			(start -0.2794 -0.1016)
			(end 0.2794 -0.1016)
			(stroke
				(width 0.1)
				(type default)
			)
			(layer "B.Fab")
		)
		(fp_line
			(start -0.2794 0.9906)
			(end -0.2794 -0.1016)
			(stroke
				(width 0.1)
				(type default)
			)
			(layer "B.Fab")
		)
		(fp_line
			(start 0.2794 -0.1016)
			(end 0.2794 0.9906)
			(stroke
				(width 0.1)
				(type default)
			)
			(layer "B.Fab")
		)
		(fp_line
			(start 0.2794 0.9906)
			(end -0.2794 0.9906)
			(stroke
				(width 0.1)
				(type default)
			)
			(layer "B.Fab")
		)
		(pad "1" smd rect
			(at 0 0 180)
			(size 0.508 0.508)
			(layers "B.Cu" "B.Mask" "B.Paste")
			(net "SGPIO_PCH_SSATA_LOAD")
		)
		(pad "2" smd rect
			(at 0 0.889 180)
			(size 0.508 0.508)
			(layers "B.Cu" "B.Mask" "B.Paste")
			(net "SGPIO_PCH_SSATA_LOAD_R")
		)
		(zone
			(layer "B.Cu")
			(hatch none 0.5)
			(connect_pads
				(clearance 0)
			)
			(min_thickness 0.25)
			(keepout
				(tracks allowed)
				(vias not_allowed)
				(pads allowed)
				(copperpour not_allowed)
				(footprints allowed)
			)
			(placement
				(enabled no)
				(sheetname "")
			)
			(fill
				(thermal_gap 0.5)
				(thermal_bridge_width 0.5)
				(island_removal_mode 0)
			)
			(polygon
				(pts
					(xy 391.16 -87.1855) (xy 390.652 -87.1855) (xy 390.652 -86.8045) (xy 391.16 -86.8045)
				)
			)
		)
		(zone
			(layer "B.Cu")
			(hatch none 0.5)
			(connect_pads
				(clearance 0)
			)
			(min_thickness 0.25)
			(keepout
				(tracks not_allowed)
				(vias allowed)
				(pads allowed)
				(copperpour not_allowed)
				(footprints allowed)
			)
			(placement
				(enabled no)
				(sheetname "")
			)
			(fill
				(thermal_gap 0.5)
				(thermal_bridge_width 0.5)
				(island_removal_mode 0)
			)
			(polygon
				(pts
					(xy 391.16 -86.8045) (xy 390.652 -86.8045) (xy 390.652 -87.1855) (xy 391.16 -87.1855)
				)
			)
		)
	)
	(footprint ""
		(layer "B.Cu")
		(at 410.7307 -8.8138 -90)
		(property "Reference" "R8D42"
			(at 0 0 90)
			(layer "B.SilkS")
			(hide yes)
			(effects
				(font
					(size 1.27 1.27)
				)
				(justify mirror)
			)
		)
		(property "Value" ""
			(at 0 0 90)
			(layer "B.Fab")
			(effects
				(font
					(size 1.27 1.27)
				)
				(justify mirror)
			)
		)
		(duplicate_pad_numbers_are_jumpers no)
		(fp_poly
			(pts
				(xy 0.2794 -0.1016) (xy -0.2794 -0.1016) (xy -0.2794 0.9906) (xy 0.2794 0.9906)
			)
			(stroke
				(width 0)
				(type default)
			)
			(fill no)
			(layer "B.CrtYd")
		)
		(fp_line
			(start -0.2794 0.9906)
			(end -0.2794 -0.1016)
			(stroke
				(width 0.1)
				(type default)
			)
			(layer "B.Fab")
		)
		(fp_line
			(start 0.2794 0.9906)
			(end -0.2794 0.9906)
			(stroke
				(width 0.1)
				(type default)
			)
			(layer "B.Fab")
		)
		(fp_line
			(start -0.2794 -0.1016)
			(end 0.2794 -0.1016)
			(stroke
				(width 0.1)
				(type default)
			)
			(layer "B.Fab")
		)
		(fp_line
			(start 0.2794 -0.1016)
			(end 0.2794 0.9906)
			(stroke
				(width 0.1)
				(type default)
			)
			(layer "B.Fab")
		)
		(pad "1" smd rect
			(at 0 0 90)
			(size 0.508 0.508)
			(layers "B.Cu" "B.Mask" "B.Paste")
			(net "PWRGD_P12V_MAIN_R")
		)
		(pad "2" smd rect
			(at 0 0.889 90)
			(size 0.508 0.508)
			(layers "B.Cu" "B.Mask" "B.Paste")
			(net "PWRGD_P12V_MAIN")
		)
		(zone
			(layer "B.Cu")
			(hatch none 0.5)
			(connect_pads
				(clearance 0)
			)
			(min_thickness 0.25)
			(keepout
				(tracks not_allowed)
				(vias allowed)
				(pads allowed)
				(copperpour not_allowed)
				(footprints allowed)
			)
			(placement
				(enabled no)
				(sheetname "")
			)
			(fill
				(thermal_gap 0.5)
				(thermal_bridge_width 0.5)
				(island_removal_mode 0)
			)
			(polygon
				(pts
					(xy 410.0957 -8.5598) (xy 410.0957 -9.0678) (xy 410.4767 -9.0678) (xy 410.4767 -8.5598)
				)
			)
		)
		(zone
			(layer "B.Cu")
			(hatch none 0.5)
			(connect_pads
				(clearance 0)
			)
			(min_thickness 0.25)
			(keepout
				(tracks allowed)
				(vias not_allowed)
				(pads allowed)
				(copperpour not_allowed)
				(footprints allowed)
			)
			(placement
				(enabled no)
				(sheetname "")
			)
			(fill
				(thermal_gap 0.5)
				(thermal_bridge_width 0.5)
				(island_removal_mode 0)
			)
			(polygon
				(pts
					(xy 410.4767 -8.5598) (xy 410.4767 -9.0678) (xy 410.0957 -9.0678) (xy 410.0957 -8.5598)
				)
			)
		)
	)
	(footprint ""
		(layer "B.Cu")
		(at 258.1656 -3.321812 -90)
		(property "Reference" "C5G54"
			(at -1.14681 0.76708 0)
			(unlocked yes)
			(layer "B.SilkS")
			(effects
				(font
					(size 0.7874 0.5842)
					(thickness 0.1524)
				)
				(justify mirror)
			)
		)
		(property "Value" ""
			(at 0 0 90)
			(layer "B.Fab")
			(effects
				(font
					(size 1.27 1.27)
				)
				(justify mirror)
			)
		)
		(duplicate_pad_numbers_are_jumpers no)
		(fp_rect
			(start 0.4953 1.6002)
			(end -0.4953 -0.2032)
			(stroke
				(width 0)
				(type default)
			)
			(fill no)
			(layer "B.CrtYd")
		)
		(fp_line
			(start -0.4953 1.6002)
			(end 0.4953 1.6002)
			(stroke
				(width 0.1)
				(type default)
			)
			(layer "B.Fab")
		)
		(fp_line
			(start 0.4953 1.6002)
			(end 0.4953 -0.2032)
			(stroke
				(width 0.1)
				(type default)
			)
			(layer "B.Fab")
		)
		(fp_line
			(start -0.4953 -0.2032)
			(end -0.4953 1.6002)
			(stroke
				(width 0.1)
				(type default)
			)
			(layer "B.Fab")
		)
		(fp_line
			(start 0.4953 -0.2032)
			(end -0.4953 -0.2032)
			(stroke
				(width 0.1)
				(type default)
			)
			(layer "B.Fab")
		)
		(pad "1" smd rect
			(at 0 0 90)
			(size 0.762 0.889)
			(layers "B.Cu" "B.Mask" "B.Paste")
			(net "PVDDQ_ABC")
		)
		(pad "2" smd rect
			(at 0 1.397 90)
			(size 0.762 0.889)
			(layers "B.Cu" "B.Mask" "B.Paste")
			(net "GND")
		)
		(zone
			(layer "B.Cu")
			(hatch none 0.5)
			(connect_pads
				(clearance 0)
			)
			(min_thickness 0.25)
			(keepout
				(tracks not_allowed)
				(vias allowed)
				(pads allowed)
				(copperpour not_allowed)
				(footprints allowed)
			)
			(placement
				(enabled no)
				(sheetname "")
			)
			(fill
				(thermal_gap 0.5)
				(thermal_bridge_width 0.5)
				(island_removal_mode 0)
			)
			(polygon
				(pts
					(xy 257.2131 -2.940812) (xy 257.7211 -2.940812) (xy 257.7211 -3.702812) (xy 257.2131 -3.702812)
				)
			)
		)
	)
)
